# S9S_MB_2U (Grand Teton) — schematic netlist excerpt (pin names and nets, part order shuffled) for the footprints in the layout excerpt that follows; sources: Cadence DE-HDL packaged netlist, KiCad conversion of 03242023_DA0F0TMBIJ0_F0T_Motherboard_J_brd_V01_OCP.brd

PR1331  Q_RES  0 5% CHIP  pkg 0402LF  page 289 : A = PVCCFA_EHV_FIVRA_CPU1_VOS1 ; B = PVCCFA_EHV_FIVRA_CPU1

(kicad_pcb
	(version 20260206)
	(generator "pcbnew")
	(generator_version "10.0")
	(general
		(thickness 1.6)
		(legacy_teardrops no)
	)
	(paper "A4")
	(title_block
		(title "03242023_DA0F0TMBIJ0_F0T_Motherboard_J_brd_V01_OCP.brd")
		(comment 1 "Grand Teton / footprints 4868-4869 of 6105")
	)
	(layers
		(0 "F.Cu" signal "TOP")
		(4 "In1.Cu" signal "GND")
		(6 "In2.Cu" signal "IN1")
		(8 "In3.Cu" signal "GND1")
		(10 "In4.Cu" signal "IN2")
		(12 "In5.Cu" signal "GND2")
		(14 "In6.Cu" signal "IN3")
		(16 "In7.Cu" signal "GND3")
		(18 "In8.Cu" signal "VCC")
		(20 "In9.Cu" signal "VCC1")
		(22 "In10.Cu" signal "GND4")
		(24 "In11.Cu" signal "IN4")
		(26 "In12.Cu" signal "GND5")
		(28 "In13.Cu" signal "IN5")
		(30 "In14.Cu" signal "GND6")
		(32 "In15.Cu" signal "IN6")
		(34 "In16.Cu" signal "GND7")
		(2 "B.Cu" signal "BOTTOM")
		(9 "F.Adhes" user "F.Adhesive")
		(11 "B.Adhes" user "B.Adhesive")
		(13 "F.Paste" user "Package Geometry/Pastemask Top")
		(15 "B.Paste" user "Package Geometry/Pastemask Bottom")
		(5 "F.SilkS" user "Ref Des/Silkscreen Top")
		(7 "B.SilkS" user "Ref Des/Silkscreen Bottom")
		(1 "F.Mask" user "Board Geometry/Soldermask Top")
		(3 "B.Mask" user "Board Geometry/Soldermask Bottom")
		(17 "Dwgs.User" user "User.Drawings")
		(19 "Cmts.User" user "User.Comments")
		(21 "Eco1.User" user "User.Eco1")
		(23 "Eco2.User" user "User.Eco2")
		(25 "Edge.Cuts" user "Board Geometry/Outline")
		(27 "Margin" user)
		(31 "F.CrtYd" user "Package Geometry/Place Bound Top")
		(29 "B.CrtYd" user "Package Geometry/Place Bound Bottom")
		(35 "F.Fab" user "Ref Des/Assembly Top")
		(33 "B.Fab" user "Ref Des/Assembly Bottom")
	)
	(footprint ""
		(layer "B.Cu")
		(at 482.66985 -184.609232 90)
		(property "Reference" "X45"
			(at -2.237232 4.72948 270)
			(unlocked yes)
			(layer "B.SilkS")
			(effects
				(font
					(size 0.7874 0.5842)
					(thickness 0.1524)
				)
				(justify left mirror)
			)
		)
		(property "Value" ""
			(at 0 0 90)
			(layer "B.Fab")
			(effects
				(font
					(size 1.27 1.27)
				)
				(justify mirror)
			)
		)
		(property "Device Type" "TP_TDR_4P_FTS_TH-TP_TDR_4P_DIPA"
			(at -1.30175 1.27 0)
			(unlocked yes)
			(layer "B.Fab")
			(hide yes)
			(effects
				(font
					(size 0.635 0.4064)
					(thickness 0.1524)
				)
				(justify mirror)
			)
		)
		(property "User Part Number" "N_A"
			(at -1.30175 1.27 0)
			(unlocked yes)
			(layer "Cmts.User")
			(hide yes)
			(effects
				(font
					(size 0.635 0.4064)
					(thickness 0.1524)
				)
				(justify mirror)
			)
		)
		(duplicate_pad_numbers_are_jumpers no)
		(fp_line
			(start 0 -1.27)
			(end 0 -0.635)
			(stroke
				(width 0.1524)
				(type default)
			)
			(layer "B.SilkS")
		)
		(fp_line
			(start -2.54 -1.27)
			(end 0 -1.27)
			(stroke
				(width 0.1524)
				(type default)
			)
			(layer "B.SilkS")
		)
		(fp_line
			(start -2.54 -1.1303)
			(end -2.54 -1.27)
			(stroke
				(width 0.1524)
				(type default)
			)
			(layer "B.SilkS")
		)
		(fp_line
			(start 0 0.635)
			(end 0 1.905)
			(stroke
				(width 0.1524)
				(type default)
			)
			(layer "B.SilkS")
		)
		(fp_line
			(start -2.54 1.4097)
			(end -2.54 1.1303)
			(stroke
				(width 0.1524)
				(type default)
			)
			(layer "B.SilkS")
		)
		(fp_line
			(start 0 3.175)
			(end 0 3.81)
			(stroke
				(width 0.1524)
				(type default)
			)
			(layer "B.SilkS")
		)
		(fp_line
			(start 0 3.81)
			(end -2.54 3.81)
			(stroke
				(width 0.1524)
				(type default)
			)
			(layer "B.SilkS")
		)
		(fp_line
			(start -2.54 3.81)
			(end -2.54 3.6703)
			(stroke
				(width 0.1524)
				(type default)
			)
			(layer "B.SilkS")
		)
		(fp_poly
			(pts
				(xy 0.761746 0) (xy 2.285746 -0.762) (xy 2.285746 0.762)
			)
			(stroke
				(width 0)
				(type default)
			)
			(fill yes)
			(layer "B.SilkS")
		)
		(fp_line
			(start 0 -1.27)
			(end 0 3.81)
			(stroke
				(width 0.1)
				(type default)
			)
			(layer "B.Fab")
		)
		(fp_line
			(start -2.54 -1.27)
			(end 0 -1.27)
			(stroke
				(width 0.1)
				(type default)
			)
			(layer "B.Fab")
		)
		(fp_line
			(start 0 3.81)
			(end -2.54 3.81)
			(stroke
				(width 0.1)
				(type default)
			)
			(layer "B.Fab")
		)
		(fp_line
			(start -2.54 3.81)
			(end -2.54 -1.27)
			(stroke
				(width 0.1)
				(type default)
			)
			(layer "B.Fab")
		)
		(fp_poly
			(pts
				(xy 0.761746 0) (xy 2.285746 -0.762) (xy 2.285746 0.762)
			)
			(stroke
				(width 0)
				(type default)
			)
			(fill yes)
			(layer "B.Fab")
		)
		(pad "1" thru_hole circle
			(at 0 0 270)
			(size 1.0033 1.0033)
			(drill 0.249936)
			(layers "*.Cu" "*.Mask")
			(remove_unused_layers no)
			(net "TDR_DIFF_85_NECK_IN4_DN")
			(clearance 0.10795)
			(padstack
				(mode front_inner_back)
				(layer "Inner"
					(shape circle)
					(size 0.8001 0.8001)
					(clearance 0.1524)
				)
				(layer "B.Cu"
					(shape circle)
					(size 1.0033 1.0033)
					(thermal_gap 0.10795)
					(clearance 0.10795)
				)
			)
		)
		(pad "2" thru_hole circle
			(at -2.54 0 270)
			(size 1.9939 1.9939)
			(drill 0.249936)
			(layers "*.Cu" "*.Mask")
			(remove_unused_layers no)
			(net "T1_GND")
			(clearance 0.10795)
			(padstack
				(mode front_inner_back)
				(layer "Inner"
					(shape circle)
					(size 0.8001 0.8001)
					(clearance 0.1524)
				)
				(layer "B.Cu"
					(shape circle)
					(size 1.9939 1.9939)
					(thermal_gap 0.10795)
					(clearance 0.10795)
				)
			)
		)
		(pad "3" thru_hole circle
			(at -2.54 2.54 270)
			(size 1.9939 1.9939)
			(drill 0.249936)
			(layers "*.Cu" "*.Mask")
			(remove_unused_layers no)
			(net "T1_GND")
			(clearance 0.10795)
			(padstack
				(mode front_inner_back)
				(layer "Inner"
					(shape circle)
					(size 0.8001 0.8001)
					(clearance 0.1524)
				)
				(layer "B.Cu"
					(shape circle)
					(size 1.9939 1.9939)
					(thermal_gap 0.10795)
					(clearance 0.10795)
				)
			)
		)
		(pad "4" thru_hole circle
			(at 0 2.54 270)
			(size 1.0033 1.0033)
			(drill 0.249936)
			(layers "*.Cu" "*.Mask")
			(remove_unused_layers no)
			(net "TDR_DIFF_85_NECK_IN4_DP")
			(clearance 0.10795)
			(padstack
				(mode front_inner_back)
				(layer "Inner"
					(shape circle)
					(size 0.8001 0.8001)
					(clearance 0.1524)
				)
				(layer "B.Cu"
					(shape circle)
					(size 1.0033 1.0033)
					(thermal_gap 0.10795)
					(clearance 0.10795)
				)
			)
		)
	)
	(footprint ""
		(layer "B.Cu")
		(at 168.133268 -356.42169 -90)
		(property "Reference" "PR1331"
			(at 0 0 90)
			(layer "B.SilkS")
			(hide yes)
			(effects
				(font
					(size 1.27 1.27)
				)
				(justify mirror)
			)
		)
		(property "Value" ""
			(at 0 0 90)
			(layer "B.Fab")
			(effects
				(font
					(size 1.27 1.27)
				)
				(justify mirror)
			)
		)
		(duplicate_pad_numbers_are_jumpers no)
		(fp_line
			(start -0.7874 0.4064)
			(end 0.7874 0.4064)
			(stroke
				(width 0.1524)
				(type default)
			)
			(layer "B.SilkS")
		)
		(fp_line
			(start 0.7874 0.4064)
			(end 0.7874 -0.4064)
			(stroke
				(width 0.1524)
				(type default)
			)
			(layer "B.SilkS")
		)
		(fp_line
			(start -0.7874 -0.4064)
			(end -0.7874 0.4064)
			(stroke
				(width 0.1524)
				(type default)
			)
			(layer "B.SilkS")
		)
		(fp_line
			(start 0.7874 -0.4064)
			(end -0.7874 -0.4064)
			(stroke
				(width 0.1524)
				(type default)
			)
			(layer "B.SilkS")
		)
		(fp_line
			(start -0.67945 0.3048)
			(end -0.120396 0.3048)
			(stroke
				(width 0.1)
				(type default)
			)
			(layer "B.Fab")
		)
		(fp_line
			(start -0.120396 0.3048)
			(end -0.120396 0.2794)
			(stroke
				(width 0.1)
				(type default)
			)
			(layer "B.Fab")
		)
		(fp_line
			(start 0.12065 0.3048)
			(end 0.67945 0.3048)
			(stroke
				(width 0.1)
				(type default)
			)
			(layer "B.Fab")
		)
		(fp_line
			(start 0.67945 0.3048)
			(end 0.67945 -0.305054)
			(stroke
				(width 0.1)
				(type default)
			)
			(layer "B.Fab")
		)
		(fp_line
			(start -0.120396 0.2794)
			(end 0.12065 0.2794)
			(stroke
				(width 0.1)
				(type default)
			)
			(layer "B.Fab")
		)
		(fp_line
			(start 0.12065 0.2794)
			(end 0.12065 0.3048)
			(stroke
				(width 0.1)
				(type default)
			)
			(layer "B.Fab")
		)
		(fp_line
			(start -0.12065 -0.2794)
			(end -0.12065 -0.3048)
			(stroke
				(width 0.1)
				(type default)
			)
			(layer "B.Fab")
		)
		(fp_line
			(start 0.12065 -0.2794)
			(end -0.12065 -0.2794)
			(stroke
				(width 0.1)
				(type default)
			)
			(layer "B.Fab")
		)
		(fp_line
			(start -0.67945 -0.3048)
			(end -0.67945 0.3048)
			(stroke
				(width 0.1)
				(type default)
			)
			(layer "B.Fab")
		)
		(fp_line
			(start -0.12065 -0.3048)
			(end -0.67945 -0.3048)
			(stroke
				(width 0.1)
				(type default)
			)
			(layer "B.Fab")
		)
		(fp_line
			(start 0.12065 -0.305054)
			(end 0.12065 -0.2794)
			(stroke
				(width 0.1)
				(type default)
			)
			(layer "B.Fab")
		)
		(fp_line
			(start 0.67945 -0.305054)
			(end 0.12065 -0.305054)
			(stroke
				(width 0.1)
				(type default)
			)
			(layer "B.Fab")
		)
		(pad "1" smd circle
			(at 0.40005 0 90)
			(size 0 0)
			(layers "B.Cu" "B.Mask" "B.Paste")
			(net "PVCCFA_EHV_FIVRA_CPU1_VOS1")
		)
		(pad "2" smd circle
			(at -0.40005 0 90)
			(size 0 0)
			(layers "B.Cu" "B.Mask" "B.Paste")
			(net "PVCCFA_EHV_FIVRA_CPU1")
		)
	)
)
